# S9S_MB_2U (Grand Teton) — schematic netlist excerpt (pin names and nets, part order shuffled) for the footprints in the layout excerpt that follows; sources: Cadence DE-HDL packaged netlist, KiCad conversion of 03242023_DA0F0TMBIJ0_F0T_Motherboard_J_brd_V01_OCP.brd

PC504_P1_5  Q_CAP  2.2UF 10V 10% X6S  pkg C0402  page 287 : A = PVCCIN_CPU1_PVCC ; B = GND
PR567  Q_RES  100 1% CHIP  pkg 0402LF  page 292 : A = VSENSE_PVCCFA_EHV_CPU1_DN ; B = GND

(kicad_pcb
	(version 20260206)
	(generator "pcbnew")
	(generator_version "10.0")
	(general
		(thickness 1.6)
		(legacy_teardrops no)
	)
	(paper "A4")
	(title_block
		(title "03242023_DA0F0TMBIJ0_F0T_Motherboard_J_brd_V01_OCP.brd")
		(comment 1 "Grand Teton / footprints 1488-1489 of 6105")
	)
	(layers
		(0 "F.Cu" signal "TOP")
		(4 "In1.Cu" signal "GND")
		(6 "In2.Cu" signal "IN1")
		(8 "In3.Cu" signal "GND1")
		(10 "In4.Cu" signal "IN2")
		(12 "In5.Cu" signal "GND2")
		(14 "In6.Cu" signal "IN3")
		(16 "In7.Cu" signal "GND3")
		(18 "In8.Cu" signal "VCC")
		(20 "In9.Cu" signal "VCC1")
		(22 "In10.Cu" signal "GND4")
		(24 "In11.Cu" signal "IN4")
		(26 "In12.Cu" signal "GND5")
		(28 "In13.Cu" signal "IN5")
		(30 "In14.Cu" signal "GND6")
		(32 "In15.Cu" signal "IN6")
		(34 "In16.Cu" signal "GND7")
		(2 "B.Cu" signal "BOTTOM")
		(9 "F.Adhes" user "F.Adhesive")
		(11 "B.Adhes" user "B.Adhesive")
		(13 "F.Paste" user "Package Geometry/Pastemask Top")
		(15 "B.Paste" user "Package Geometry/Pastemask Bottom")
		(5 "F.SilkS" user "Ref Des/Silkscreen Top")
		(7 "B.SilkS" user "Ref Des/Silkscreen Bottom")
		(1 "F.Mask" user "Board Geometry/Soldermask Top")
		(3 "B.Mask" user "Board Geometry/Soldermask Bottom")
		(17 "Dwgs.User" user "User.Drawings")
		(19 "Cmts.User" user "User.Comments")
		(21 "Eco1.User" user "User.Eco1")
		(23 "Eco2.User" user "User.Eco2")
		(25 "Edge.Cuts" user "Board Geometry/Outline")
		(27 "Margin" user)
		(31 "F.CrtYd" user "Package Geometry/Place Bound Top")
		(29 "B.CrtYd" user "Package Geometry/Place Bound Bottom")
		(35 "F.Fab" user "Ref Des/Assembly Top")
		(33 "B.Fab" user "Ref Des/Assembly Bottom")
	)
	(footprint ""
		(layer "F.Cu")
		(at 73.506076 -174.903638 180)
		(property "Reference" "PR567"
			(at 0 0 180)
			(layer "F.SilkS")
			(hide yes)
			(effects
				(font
					(size 1.27 1.27)
				)
			)
		)
		(property "Value" ""
			(at 0 0 180)
			(layer "F.Fab")
			(effects
				(font
					(size 1.27 1.27)
				)
			)
		)
		(duplicate_pad_numbers_are_jumpers no)
		(fp_line
			(start 0.7874 0.4064)
			(end -0.7874 0.4064)
			(stroke
				(width 0.1524)
				(type default)
			)
			(layer "F.SilkS")
		)
		(fp_line
			(start 0.7874 -0.4064)
			(end 0.7874 0.4064)
			(stroke
				(width 0.1524)
				(type default)
			)
			(layer "F.SilkS")
		)
		(fp_line
			(start -0.7874 0.4064)
			(end -0.7874 -0.4064)
			(stroke
				(width 0.1524)
				(type default)
			)
			(layer "F.SilkS")
		)
		(fp_line
			(start -0.7874 -0.4064)
			(end 0.7874 -0.4064)
			(stroke
				(width 0.1524)
				(type default)
			)
			(layer "F.SilkS")
		)
		(fp_line
			(start 0.67945 0.3048)
			(end 0.120396 0.3048)
			(stroke
				(width 0.1)
				(type default)
			)
			(layer "F.Fab")
		)
		(fp_line
			(start 0.67945 -0.3048)
			(end 0.67945 0.3048)
			(stroke
				(width 0.1)
				(type default)
			)
			(layer "F.Fab")
		)
		(fp_line
			(start 0.12065 -0.2794)
			(end 0.12065 -0.3048)
			(stroke
				(width 0.1)
				(type default)
			)
			(layer "F.Fab")
		)
		(fp_line
			(start 0.12065 -0.3048)
			(end 0.67945 -0.3048)
			(stroke
				(width 0.1)
				(type default)
			)
			(layer "F.Fab")
		)
		(fp_line
			(start 0.120396 0.3048)
			(end 0.120396 0.2794)
			(stroke
				(width 0.1)
				(type default)
			)
			(layer "F.Fab")
		)
		(fp_line
			(start 0.120396 0.2794)
			(end -0.12065 0.2794)
			(stroke
				(width 0.1)
				(type default)
			)
			(layer "F.Fab")
		)
		(fp_line
			(start -0.12065 0.3048)
			(end -0.67945 0.3048)
			(stroke
				(width 0.1)
				(type default)
			)
			(layer "F.Fab")
		)
		(fp_line
			(start -0.12065 0.2794)
			(end -0.12065 0.3048)
			(stroke
				(width 0.1)
				(type default)
			)
			(layer "F.Fab")
		)
		(fp_line
			(start -0.12065 -0.2794)
			(end 0.12065 -0.2794)
			(stroke
				(width 0.1)
				(type default)
			)
			(layer "F.Fab")
		)
		(fp_line
			(start -0.12065 -0.305054)
			(end -0.12065 -0.2794)
			(stroke
				(width 0.1)
				(type default)
			)
			(layer "F.Fab")
		)
		(fp_line
			(start -0.67945 0.3048)
			(end -0.67945 -0.305054)
			(stroke
				(width 0.1)
				(type default)
			)
			(layer "F.Fab")
		)
		(fp_line
			(start -0.67945 -0.305054)
			(end -0.12065 -0.305054)
			(stroke
				(width 0.1)
				(type default)
			)
			(layer "F.Fab")
		)
		(pad "1" smd circle
			(at -0.40005 0 180)
			(size 0 0)
			(layers "F.Cu" "F.Mask" "F.Paste")
			(net "VSENSE_PVCCFA_EHV_CPU1_DN")
		)
		(pad "2" smd circle
			(at 0.40005 0 180)
			(size 0 0)
			(layers "F.Cu" "F.Mask" "F.Paste")
			(net "GND")
		)
	)
	(footprint ""
		(layer "F.Cu")
		(at 126.065026 -336.935572 -90)
		(property "Reference" "PC504_P1_5"
			(at 0 0 270)
			(layer "F.SilkS")
			(hide yes)
			(effects
				(font
					(size 1.27 1.27)
				)
			)
		)
		(property "Value" ""
			(at 0 0 270)
			(layer "F.Fab")
			(effects
				(font
					(size 1.27 1.27)
				)
			)
		)
		(duplicate_pad_numbers_are_jumpers no)
		(fp_line
			(start -0.7874 0.4064)
			(end -0.7874 -0.4064)
			(stroke
				(width 0.1524)
				(type default)
			)
			(layer "F.SilkS")
		)
		(fp_line
			(start 0.7874 0.4064)
			(end -0.7874 0.4064)
			(stroke
				(width 0.1524)
				(type default)
			)
			(layer "F.SilkS")
		)
		(fp_line
			(start -0.7874 -0.4064)
			(end 0.7874 -0.4064)
			(stroke
				(width 0.1524)
				(type default)
			)
			(layer "F.SilkS")
		)
		(fp_line
			(start 0.7874 -0.4064)
			(end 0.7874 0.4064)
			(stroke
				(width 0.1524)
				(type default)
			)
			(layer "F.SilkS")
		)
		(fp_line
			(start -0.67945 0.3048)
			(end -0.67945 -0.305054)
			(stroke
				(width 0.1)
				(type default)
			)
			(layer "F.Fab")
		)
		(fp_line
			(start -0.12065 0.3048)
			(end -0.67945 0.3048)
			(stroke
				(width 0.1)
				(type default)
			)
			(layer "F.Fab")
		)
		(fp_line
			(start 0.120396 0.3048)
			(end 0.120396 0.2794)
			(stroke
				(width 0.1)
				(type default)
			)
			(layer "F.Fab")
		)
		(fp_line
			(start 0.67945 0.3048)
			(end 0.120396 0.3048)
			(stroke
				(width 0.1)
				(type default)
			)
			(layer "F.Fab")
		)
		(fp_line
			(start -0.12065 0.2794)
			(end -0.12065 0.3048)
			(stroke
				(width 0.1)
				(type default)
			)
			(layer "F.Fab")
		)
		(fp_line
			(start 0.120396 0.2794)
			(end -0.12065 0.2794)
			(stroke
				(width 0.1)
				(type default)
			)
			(layer "F.Fab")
		)
		(fp_line
			(start -0.12065 -0.2794)
			(end 0.12065 -0.2794)
			(stroke
				(width 0.1)
				(type default)
			)
			(layer "F.Fab")
		)
		(fp_line
			(start 0.12065 -0.2794)
			(end 0.12065 -0.3048)
			(stroke
				(width 0.1)
				(type default)
			)
			(layer "F.Fab")
		)
		(fp_line
			(start 0.12065 -0.3048)
			(end 0.67945 -0.3048)
			(stroke
				(width 0.1)
				(type default)
			)
			(layer "F.Fab")
		)
		(fp_line
			(start 0.67945 -0.3048)
			(end 0.67945 0.3048)
			(stroke
				(width 0.1)
				(type default)
			)
			(layer "F.Fab")
		)
		(fp_line
			(start -0.67945 -0.305054)
			(end -0.12065 -0.305054)
			(stroke
				(width 0.1)
				(type default)
			)
			(layer "F.Fab")
		)
		(fp_line
			(start -0.12065 -0.305054)
			(end -0.12065 -0.2794)
			(stroke
				(width 0.1)
				(type default)
			)
			(layer "F.Fab")
		)
		(pad "1" smd circle
			(at -0.40005 0 270)
			(size 0 0)
			(layers "F.Cu" "F.Mask" "F.Paste")
			(net "PVCCIN_CPU1_PVCC")
		)
		(pad "2" smd circle
			(at 0.40005 0 270)
			(size 0 0)
			(layers "F.Cu" "F.Mask" "F.Paste")
			(net "GND")
		)
	)
)
